# T6G (Grand Teton) — schematic netlist excerpt (pin names and nets, part order shuffled) for the footprints in the layout excerpt that follows; sources: Cadence DE-HDL packaged netlist, KiCad conversion of 04192023_DAF0TMB3IC0_F0TG_MB_C_brd_V02_OCP.brd

R3163  Q_RES  4.7K 1% EMPTY  pkg 0402LF  page 137 : A = OCP_V3_2_ID0 ; B = GND
C6054  Q_CAP  0.001UF 50V 10% X7R  pkg C0402  page 177 : A = P1V2_AUX ; B = GND

(kicad_pcb
	(version 20260206)
	(generator "pcbnew")
	(generator_version "10.0")
	(general
		(thickness 1.6)
		(legacy_teardrops no)
	)
	(paper "A4")
	(title_block
		(title "04192023_DAF0TMB3IC0_F0TG_MB_C_brd_V02_OCP.brd")
		(comment 1 "Grand Teton / footprints 5703-5704 of 8354")
	)
	(layers
		(0 "F.Cu" signal "TOP")
		(4 "In1.Cu" signal "GND")
		(6 "In2.Cu" signal "IN1")
		(8 "In3.Cu" signal "GND1")
		(10 "In4.Cu" signal "IN2")
		(12 "In5.Cu" signal "GND2")
		(14 "In6.Cu" signal "IN3")
		(16 "In7.Cu" signal "GND3")
		(18 "In8.Cu" signal "VCC")
		(20 "In9.Cu" signal "VCC1")
		(22 "In10.Cu" signal "GND4")
		(24 "In11.Cu" signal "IN4")
		(26 "In12.Cu" signal "GND5")
		(28 "In13.Cu" signal "IN5")
		(30 "In14.Cu" signal "GND6")
		(32 "In15.Cu" signal "IN6")
		(34 "In16.Cu" signal "GND7")
		(2 "B.Cu" signal "BOTTOM")
		(9 "F.Adhes" user "F.Adhesive")
		(11 "B.Adhes" user "B.Adhesive")
		(13 "F.Paste" user "Package Geometry/Pastemask Top")
		(15 "B.Paste" user "Package Geometry/Pastemask Bottom")
		(5 "F.SilkS" user "Ref Des/Silkscreen Top")
		(7 "B.SilkS" user "Ref Des/Silkscreen Bottom")
		(1 "F.Mask" user "Board Geometry/Soldermask Top")
		(3 "B.Mask" user "Board Geometry/Soldermask Bottom")
		(17 "Dwgs.User" user "User.Drawings")
		(19 "Cmts.User" user "User.Comments")
		(21 "Eco1.User" user "User.Eco1")
		(23 "Eco2.User" user "User.Eco2")
		(25 "Edge.Cuts" user "Board Geometry/Outline")
		(27 "Margin" user)
		(31 "F.CrtYd" user "Package Geometry/Place Bound Top")
		(29 "B.CrtYd" user "Package Geometry/Place Bound Bottom")
		(35 "F.Fab" user "Ref Des/Assembly Top")
		(33 "B.Fab" user "Ref Des/Assembly Bottom")
	)
	(footprint ""
		(layer "B.Cu")
		(at 128.505204 -35.686492 180)
		(property "Reference" "C6054"
			(at 0 0 0)
			(layer "B.SilkS")
			(hide yes)
			(effects
				(font
					(size 1.27 1.27)
				)
				(justify mirror)
			)
		)
		(property "Value" ""
			(at 0 0 0)
			(layer "B.Fab")
			(effects
				(font
					(size 1.27 1.27)
				)
				(justify mirror)
			)
		)
		(duplicate_pad_numbers_are_jumpers no)
		(fp_line
			(start 0.7874 0.4064)
			(end 0.7874 -0.4064)
			(stroke
				(width 0.1524)
				(type default)
			)
			(layer "B.SilkS")
		)
		(fp_line
			(start 0.7874 -0.4064)
			(end -0.7874 -0.4064)
			(stroke
				(width 0.1524)
				(type default)
			)
			(layer "B.SilkS")
		)
		(fp_line
			(start -0.7874 0.4064)
			(end 0.7874 0.4064)
			(stroke
				(width 0.1524)
				(type default)
			)
			(layer "B.SilkS")
		)
		(fp_line
			(start -0.7874 -0.4064)
			(end -0.7874 0.4064)
			(stroke
				(width 0.1524)
				(type default)
			)
			(layer "B.SilkS")
		)
		(fp_line
			(start 0.67945 0.3048)
			(end 0.67945 -0.305054)
			(stroke
				(width 0.1)
				(type default)
			)
			(layer "B.Fab")
		)
		(fp_line
			(start 0.67945 -0.305054)
			(end 0.12065 -0.305054)
			(stroke
				(width 0.1)
				(type default)
			)
			(layer "B.Fab")
		)
		(fp_line
			(start 0.12065 0.3048)
			(end 0.67945 0.3048)
			(stroke
				(width 0.1)
				(type default)
			)
			(layer "B.Fab")
		)
		(fp_line
			(start 0.12065 0.2794)
			(end 0.12065 0.3048)
			(stroke
				(width 0.1)
				(type default)
			)
			(layer "B.Fab")
		)
		(fp_line
			(start 0.12065 -0.2794)
			(end -0.12065 -0.2794)
			(stroke
				(width 0.1)
				(type default)
			)
			(layer "B.Fab")
		)
		(fp_line
			(start 0.12065 -0.305054)
			(end 0.12065 -0.2794)
			(stroke
				(width 0.1)
				(type default)
			)
			(layer "B.Fab")
		)
		(fp_line
			(start -0.120396 0.3048)
			(end -0.120396 0.2794)
			(stroke
				(width 0.1)
				(type default)
			)
			(layer "B.Fab")
		)
		(fp_line
			(start -0.120396 0.2794)
			(end 0.12065 0.2794)
			(stroke
				(width 0.1)
				(type default)
			)
			(layer "B.Fab")
		)
		(fp_line
			(start -0.12065 -0.2794)
			(end -0.12065 -0.3048)
			(stroke
				(width 0.1)
				(type default)
			)
			(layer "B.Fab")
		)
		(fp_line
			(start -0.12065 -0.3048)
			(end -0.67945 -0.3048)
			(stroke
				(width 0.1)
				(type default)
			)
			(layer "B.Fab")
		)
		(fp_line
			(start -0.67945 0.3048)
			(end -0.120396 0.3048)
			(stroke
				(width 0.1)
				(type default)
			)
			(layer "B.Fab")
		)
		(fp_line
			(start -0.67945 -0.3048)
			(end -0.67945 0.3048)
			(stroke
				(width 0.1)
				(type default)
			)
			(layer "B.Fab")
		)
		(pad "1" smd circle
			(at 0.40005 0)
			(size 0 0)
			(layers "B.Cu" "B.Mask" "B.Paste")
			(net "P1V2_AUX")
		)
		(pad "2" smd circle
			(at -0.40005 0)
			(size 0 0)
			(layers "B.Cu" "B.Mask" "B.Paste")
			(net "GND")
		)
	)
	(footprint ""
		(layer "B.Cu")
		(at 72.825864 -11.26871 90)
		(property "Reference" "R3163"
			(at 0 0 90)
			(layer "B.SilkS")
			(hide yes)
			(effects
				(font
					(size 1.27 1.27)
				)
				(justify mirror)
			)
		)
		(property "Value" ""
			(at 0 0 90)
			(layer "B.Fab")
			(effects
				(font
					(size 1.27 1.27)
				)
				(justify mirror)
			)
		)
		(duplicate_pad_numbers_are_jumpers no)
		(fp_line
			(start 0.7874 -0.4064)
			(end -0.7874 -0.4064)
			(stroke
				(width 0.1524)
				(type default)
			)
			(layer "B.SilkS")
		)
		(fp_line
			(start -0.7874 -0.4064)
			(end -0.7874 0.4064)
			(stroke
				(width 0.1524)
				(type default)
			)
			(layer "B.SilkS")
		)
		(fp_line
			(start 0.7874 0.4064)
			(end 0.7874 -0.4064)
			(stroke
				(width 0.1524)
				(type default)
			)
			(layer "B.SilkS")
		)
		(fp_line
			(start -0.7874 0.4064)
			(end 0.7874 0.4064)
			(stroke
				(width 0.1524)
				(type default)
			)
			(layer "B.SilkS")
		)
		(fp_line
			(start 0.67945 -0.305054)
			(end 0.12065 -0.305054)
			(stroke
				(width 0.1)
				(type default)
			)
			(layer "B.Fab")
		)
		(fp_line
			(start 0.12065 -0.305054)
			(end 0.12065 -0.2794)
			(stroke
				(width 0.1)
				(type default)
			)
			(layer "B.Fab")
		)
		(fp_line
			(start -0.12065 -0.3048)
			(end -0.67945 -0.3048)
			(stroke
				(width 0.1)
				(type default)
			)
			(layer "B.Fab")
		)
		(fp_line
			(start -0.67945 -0.3048)
			(end -0.67945 0.3048)
			(stroke
				(width 0.1)
				(type default)
			)
			(layer "B.Fab")
		)
		(fp_line
			(start 0.12065 -0.2794)
			(end -0.12065 -0.2794)
			(stroke
				(width 0.1)
				(type default)
			)
			(layer "B.Fab")
		)
		(fp_line
			(start -0.12065 -0.2794)
			(end -0.12065 -0.3048)
			(stroke
				(width 0.1)
				(type default)
			)
			(layer "B.Fab")
		)
		(fp_line
			(start 0.12065 0.2794)
			(end 0.12065 0.3048)
			(stroke
				(width 0.1)
				(type default)
			)
			(layer "B.Fab")
		)
		(fp_line
			(start -0.120396 0.2794)
			(end 0.12065 0.2794)
			(stroke
				(width 0.1)
				(type default)
			)
			(layer "B.Fab")
		)
		(fp_line
			(start 0.67945 0.3048)
			(end 0.67945 -0.305054)
			(stroke
				(width 0.1)
				(type default)
			)
			(layer "B.Fab")
		)
		(fp_line
			(start 0.12065 0.3048)
			(end 0.67945 0.3048)
			(stroke
				(width 0.1)
				(type default)
			)
			(layer "B.Fab")
		)
		(fp_line
			(start -0.120396 0.3048)
			(end -0.120396 0.2794)
			(stroke
				(width 0.1)
				(type default)
			)
			(layer "B.Fab")
		)
		(fp_line
			(start -0.67945 0.3048)
			(end -0.120396 0.3048)
			(stroke
				(width 0.1)
				(type default)
			)
			(layer "B.Fab")
		)
		(pad "1" smd circle
			(at 0.40005 0 270)
			(size 0 0)
			(layers "B.Cu" "B.Mask" "B.Paste")
			(net "OCP_V3_2_ID0")
		)
		(pad "2" smd circle
			(at -0.40005 0 270)
			(size 0 0)
			(layers "B.Cu" "B.Mask" "B.Paste")
			(net "GND")
		)
	)
)
